(kicad_pcb
	(version 20241229)
	(generator "pcbnew")
	(generator_version "9.0")
	(general
		(thickness 1.63)
		(legacy_teardrops no)
	)
	(paper "A4")
	(title_block
		(title "CM4 Baseboard")
		(date "2026-01-05")
		(rev "1.1.1")
		(company "Antmicro Ltd")
		(comment 1 "www.antmicro.com")
		(comment 9 "footprints 256-260 of 506")
	)
	(layers
		(0 "F.Cu" signal)
		(4 "In1.Cu" power)
		(6 "In2.Cu" power)
		(8 "In3.Cu" signal)
		(10 "In4.Cu" signal)
		(2 "B.Cu" signal)
		(9 "F.Adhes" user "F.Adhesive")
		(11 "B.Adhes" user "B.Adhesive")
		(13 "F.Paste" user)
		(15 "B.Paste" user)
		(5 "F.SilkS" user "F.Silkscreen")
		(7 "B.SilkS" user "B.Silkscreen")
		(1 "F.Mask" user)
		(3 "B.Mask" user)
		(17 "Dwgs.User" user "User.Drawings")
		(19 "Cmts.User" user "User.Comments")
		(21 "Eco1.User" user "User.Eco1")
		(23 "Eco2.User" user "User.Eco2")
		(25 "Edge.Cuts" user)
		(27 "Margin" user)
		(31 "F.CrtYd" user "F.Courtyard")
		(29 "B.CrtYd" user "B.Courtyard")
		(35 "F.Fab" user)
		(33 "B.Fab" user)
	)
	(footprint "antmicro-footprints:R_0402_1005Metric"
		(layer "F.Cu")
		(at 142.727962 126.4565 180)
		(descr "Resistor SMD 0402")
		(tags "resistor SMD 0402")
		(property "Reference" "R211"
			(at -1.07 -0.37 90)
			(layer "F.SilkS")
			(effects
				(font
					(size 0.7 0.7)
					(thickness 0.15)
				)
				(justify right bottom)
			)
		)
		(property "Value" "R_470R_0402"
			(at -1.011843 1.772047 0)
			(layer "F.Fab")
			(effects
				(font
					(size 0.7 0.7)
					(thickness 0.15)
				)
				(justify right bottom)
			)
		)
		(property "Datasheet" "https://www.bourns.com/docs/product-datasheets/cr.pdf"
			(at 0 0 180)
			(layer "F.Fab")
			(hide yes)
			(effects
				(font
					(size 1.27 1.27)
					(thickness 0.15)
				)
			)
		)
		(property "Manufacturer" "Bourns"
			(at 0 0 180)
			(unlocked yes)
			(layer "F.Fab")
			(hide yes)
			(effects
				(font
					(size 1 1)
					(thickness 0.15)
				)
			)
		)
		(property "MPN" "CR0402-FX-4700GLF"
			(at 0 0 180)
			(unlocked yes)
			(layer "F.Fab")
			(hide yes)
			(effects
				(font
					(size 1 1)
					(thickness 0.15)
				)
			)
		)
		(property "Val" "470R"
			(at 0 0 180)
			(unlocked yes)
			(layer "F.Fab")
			(hide yes)
			(effects
				(font
					(size 1 1)
					(thickness 0.15)
				)
			)
		)
		(property "License" "Apache-2.0"
			(at 0 0 180)
			(unlocked yes)
			(layer "F.Fab")
			(hide yes)
			(effects
				(font
					(size 1 1)
					(thickness 0.15)
				)
			)
		)
		(property "Author" "Antmicro"
			(at 0 0 180)
			(unlocked yes)
			(layer "F.Fab")
			(hide yes)
			(effects
				(font
					(size 1 1)
					(thickness 0.15)
				)
			)
		)
		(property "Tolerance" "1%"
			(at 0 0 180)
			(unlocked yes)
			(layer "F.Fab")
			(hide yes)
			(effects
				(font
					(size 1 1)
					(thickness 0.15)
				)
			)
		)
		(sheetname "/Compute module/")
		(sheetfile "compute-module.kicad_sch")
		(attr smd)
		(fp_rect
			(start -0.925 -0.47)
			(end 0.925 0.47)
			(stroke
				(width 0.05)
				(type default)
			)
			(fill no)
			(layer "F.CrtYd")
		)
		(fp_rect
			(start -0.5 -0.25)
			(end 0.5 0.25)
			(stroke
				(width 0.15)
				(type solid)
			)
			(fill no)
			(layer "F.Fab")
		)
		(fp_text user "${REFERENCE}"
			(at -0.95 3.168 180)
			(layer "F.Fab")
			(effects
				(font
					(size 0.7 0.7)
					(thickness 0.15)
				)
				(justify left bottom)
			)
		)
		(fp_text user "Author: Antmicro"
			(at -0.95 4.169 180)
			(layer "F.Fab")
			(effects
				(font
					(size 0.7 0.7)
					(thickness 0.15)
				)
				(justify left bottom)
			)
		)
		(fp_text user "License: Apache-2.0"
			(at -0.95 5.169 180)
			(layer "F.Fab")
			(effects
				(font
					(size 0.7 0.7)
					(thickness 0.15)
				)
				(justify left bottom)
			)
		)
		(pad "1" smd roundrect
			(at -0.48 0 180)
			(size 0.59 0.64)
			(layers "F.Cu" "F.Mask" "F.Paste")
			(roundrect_rratio 0.25)
			(net 342 "Net-(R211-Pad1)")
			(pintype "passive")
		)
		(pad "2" smd roundrect
			(at 0.48 0 180)
			(size 0.59 0.64)
			(layers "F.Cu" "F.Mask" "F.Paste")
			(roundrect_rratio 0.25)
			(net 329 "Net-(Q207-G)")
			(pintype "passive")
		)
	)
	(footprint "antmicro-footprints:Choke_Murata-DLW21"
		(layer "F.Cu")
		(at 93.518962 124.153999 -90)
		(property "Reference" "T901"
			(at -2.21957 1.012162 90)
			(layer "F.SilkS")
			(effects
				(font
					(size 0.7 0.7)
					(thickness 0.15)
				)
				(justify right bottom)
			)
		)
		(property "Value" "Choke_DLW21SN900SQ2L"
			(at 0.4 1.778 90)
			(layer "F.Fab")
			(effects
				(font
					(size 0.7 0.7)
					(thickness 0.15)
				)
				(justify right bottom)
			)
		)
		(property "Datasheet" "https://www.murata.com/en-us/products/productdetail?partno=DLW21SN900SQ2%23"
			(at 0 0 270)
			(layer "F.Fab")
			(hide yes)
			(effects
				(font
					(size 1.27 1.27)
					(thickness 0.15)
				)
			)
		)
		(property "Manufacturer" "Murata"
			(at 0 0 270)
			(unlocked yes)
			(layer "F.Fab")
			(hide yes)
			(effects
				(font
					(size 1 1)
					(thickness 0.15)
				)
			)
		)
		(property "MPN" "DLW21SN900SQ2L"
			(at 0 0 270)
			(unlocked yes)
			(layer "F.Fab")
			(hide yes)
			(effects
				(font
					(size 1 1)
					(thickness 0.15)
				)
			)
		)
		(property "IMax" "0.33 A"
			(at 0 0 270)
			(unlocked yes)
			(layer "F.Fab")
			(hide yes)
			(effects
				(font
					(size 1 1)
					(thickness 0.15)
				)
			)
		)
		(property "Author" "Antmicro"
			(at 0 0 270)
			(unlocked yes)
			(layer "F.Fab")
			(hide yes)
			(effects
				(font
					(size 1 1)
					(thickness 0.15)
				)
			)
		)
		(property "License" "Apache-2.0"
			(at 0 0 270)
			(unlocked yes)
			(layer "F.Fab")
			(hide yes)
			(effects
				(font
					(size 1 1)
					(thickness 0.15)
				)
			)
		)
		(property ki_fp_filters "IND_ACM9070_TDK")
		(sheetname "/USB/")
		(sheetfile "usb.kicad_sch")
		(attr smd)
		(fp_line
			(start 1 0.8)
			(end -1 0.8)
			(stroke
				(width 0.15)
				(type solid)
			)
			(layer "F.SilkS")
		)
		(fp_line
			(start -1 -0.8)
			(end 1 -0.8)
			(stroke
				(width 0.15)
				(type solid)
			)
			(layer "F.SilkS")
		)
		(fp_circle
			(center -1.475 0.775)
			(end -1.425 0.775)
			(stroke
				(width 0.15)
				(type solid)
			)
			(fill yes)
			(layer "F.SilkS")
		)
		(fp_rect
			(start -1.55 -0.85)
			(end 1.55 0.85)
			(stroke
				(width 0.05)
				(type solid)
			)
			(fill no)
			(layer "F.CrtYd")
		)
		(fp_line
			(start -1 0.35)
			(end -0.75 0.6)
			(stroke
				(width 0.15)
				(type solid)
			)
			(layer "F.Fab")
		)
		(fp_rect
			(start -1 -0.6)
			(end 1 0.6)
			(stroke
				(width 0.15)
				(type solid)
			)
			(fill no)
			(layer "F.Fab")
		)
		(fp_text user "License: Apache-2.0"
			(at -1.55 6.178 270)
			(layer "F.Fab")
			(effects
				(font
					(size 0.7 0.7)
					(thickness 0.15)
				)
				(justify left bottom)
			)
		)
		(fp_text user "Author: Antmicro"
			(at -1.55 4.978 270)
			(layer "F.Fab")
			(effects
				(font
					(size 0.7 0.7)
					(thickness 0.15)
				)
				(justify left bottom)
			)
		)
		(fp_text user "${REFERENCE}"
			(at -1.55 3.778 270)
			(layer "F.Fab")
			(effects
				(font
					(size 0.7 0.7)
					(thickness 0.15)
				)
				(justify left bottom)
			)
		)
		(pad "1" smd roundrect
			(at -0.85 0.4 270)
			(size 0.9 0.4)
			(layers "F.Cu" "F.Mask" "F.Paste")
			(roundrect_rratio 0.1)
			(net 205 "/USB/AD_P")
			(pinfunction "1")
			(pintype "passive")
		)
		(pad "2" smd roundrect
			(at 0.85 0.4 270)
			(size 0.9 0.4)
			(layers "F.Cu" "F.Mask" "F.Paste")
			(roundrect_rratio 0.1)
			(net 39 "/Compute module/USB.D_P")
			(pinfunction "2")
			(pintype "passive")
		)
		(pad "3" smd roundrect
			(at 0.85 -0.4 270)
			(size 0.9 0.4)
			(layers "F.Cu" "F.Mask" "F.Paste")
			(roundrect_rratio 0.1)
			(net 38 "/Compute module/USB.D_N")
			(pinfunction "3")
			(pintype "passive")
		)
		(pad "4" smd roundrect
			(at -0.85 -0.4 270)
			(size 0.9 0.4)
			(layers "F.Cu" "F.Mask" "F.Paste")
			(roundrect_rratio 0.1)
			(net 206 "/USB/AD_N")
			(pinfunction "4")
			(pintype "passive")
		)
	)
	(footprint "antmicro-footprints:SOT-523"
		(layer "F.Cu")
		(at 79.792962 169.8415 90)
		(property "Reference" "Q208"
			(at -1.6985 1.657038 180)
			(layer "F.SilkS")
			(effects
				(font
					(size 0.7 0.7)
					(thickness 0.15)
				)
				(justify left bottom)
			)
		)
		(property "Value" "PJE138K"
			(at 0.1 1.824 90)
			(layer "F.Fab")
			(effects
				(font
					(size 0.7 0.7)
					(thickness 0.15)
				)
				(justify left bottom)
			)
		)
		(property "Datasheet" "https://www.mouser.com/datasheet/2/1057/PJE138K-1876698.pdf"
			(at 0 0 90)
			(layer "F.Fab")
			(hide yes)
			(effects
				(font
					(size 1.27 1.27)
					(thickness 0.15)
				)
			)
		)
		(property "MPN" "PJE138K_R1_00001"
			(at 0 0 90)
			(unlocked yes)
			(layer "F.Fab")
			(hide yes)
			(effects
				(font
					(size 1 1)
					(thickness 0.15)
				)
			)
		)
		(property "Manufacturer" "PANJIT"
			(at 0 0 90)
			(unlocked yes)
			(layer "F.Fab")
			(hide yes)
			(effects
				(font
					(size 1 1)
					(thickness 0.15)
				)
			)
		)
		(property "Author" "Antmicro"
			(at 0 0 90)
			(unlocked yes)
			(layer "F.Fab")
			(hide yes)
			(effects
				(font
					(size 1 1)
					(thickness 0.15)
				)
			)
		)
		(property "License" "Apache-2.0"
			(at 0 0 90)
			(unlocked yes)
			(layer "F.Fab")
			(hide yes)
			(effects
				(font
					(size 1 1)
					(thickness 0.15)
				)
			)
		)
		(sheetname "/Compute module/")
		(sheetfile "compute-module.kicad_sch")
		(attr smd)
		(fp_line
			(start -0.277 -0.551)
			(end -0.277 -0.75)
			(stroke
				(width 0.15)
				(type solid)
			)
			(layer "F.SilkS")
		)
		(fp_line
			(start -0.725 -0.551)
			(end -0.277 -0.551)
			(stroke
				(width 0.15)
				(type solid)
			)
			(layer "F.SilkS")
		)
		(fp_line
			(start -0.927 -0.351)
			(end -0.725 -0.551)
			(stroke
				(width 0.15)
				(type solid)
			)
			(layer "F.SilkS")
		)
		(fp_line
			(start -0.927 -0.051)
			(end -0.927 -0.351)
			(stroke
				(width 0.15)
				(type solid)
			)
			(layer "F.SilkS")
		)
		(fp_circle
			(center -0.9652 0.9652)
			(end -0.9152 0.9652)
			(stroke
				(width 0.15)
				(type solid)
			)
			(fill yes)
			(layer "F.SilkS")
		)
		(fp_line
			(start 1.1 -1.16)
			(end 1.1 1.15)
			(stroke
				(width 0.05)
				(type solid)
			)
			(layer "F.CrtYd")
		)
		(fp_line
			(start -1.12 -1.16)
			(end 1.1 -1.16)
			(stroke
				(width 0.05)
				(type solid)
			)
			(layer "F.CrtYd")
		)
		(fp_line
			(start -1.12 -1.16)
			(end -1.12 1.15)
			(stroke
				(width 0.05)
				(type solid)
			)
			(layer "F.CrtYd")
		)
		(fp_line
			(start -1.12 1.15)
			(end 1.1 1.15)
			(stroke
				(width 0.05)
				(type solid)
			)
			(layer "F.CrtYd")
		)
		(fp_line
			(start 0.8 -0.425)
			(end -0.652 -0.425)
			(stroke
				(width 0.15)
				(type solid)
			)
			(layer "F.Fab")
		)
		(fp_line
			(start 0.8 -0.425)
			(end 0.8 0.424)
			(stroke
				(width 0.15)
				(type solid)
			)
			(layer "F.Fab")
		)
		(fp_line
			(start -0.652 -0.425)
			(end -0.802 -0.276)
			(stroke
				(width 0.15)
				(type solid)
			)
			(layer "F.Fab")
		)
		(fp_line
			(start -0.802 -0.276)
			(end -0.802 0.424)
			(stroke
				(width 0.15)
				(type solid)
			)
			(layer "F.Fab")
		)
		(fp_line
			(start 0.8 0.424)
			(end -0.802 0.424)
			(stroke
				(width 0.15)
				(type solid)
			)
			(layer "F.Fab")
		)
		(fp_circle
			(center -0.9652 0.9652)
			(end -0.9144 0.9652)
			(stroke
				(width 0.15)
				(type solid)
			)
			(fill no)
			(layer "F.Fab")
		)
		(fp_text user "${REFERENCE}"
			(at -1.12 3.824 90)
			(layer "F.Fab")
			(effects
				(font
					(size 0.7 0.7)
					(thickness 0.15)
				)
				(justify left bottom)
			)
		)
		(fp_text user "License: Apache-2.0"
			(at -1.12 5.024 90)
			(layer "F.Fab")
			(effects
				(font
					(size 0.7 0.7)
					(thickness 0.15)
				)
				(justify left bottom)
			)
		)
		(fp_text user "Author: Antmicro"
			(at -1.12 6.224 90)
			(layer "F.Fab")
			(effects
				(font
					(size 0.7 0.7)
					(thickness 0.15)
				)
				(justify left bottom)
			)
		)
		(pad "1" smd rect
			(at -0.5 0.65 90)
			(size 0.4 0.51)
			(layers "F.Cu" "F.Mask" "F.Paste")
			(net 2 "Net-(D203-A)")
			(pinfunction "G")
			(pintype "input")
		)
		(pad "2" smd rect
			(at 0.498 0.65 90)
			(size 0.4 0.51)
			(layers "F.Cu" "F.Mask" "F.Paste")
			(net 3 "GND")
			(pinfunction "S")
			(pintype "passive")
		)
		(pad "3" smd rect
			(at 0 -0.652 90)
			(size 0.4 0.51)
			(layers "F.Cu" "F.Mask" "F.Paste")
			(net 255 "/Compute module/~{RPi_RST}")
			(pinfunction "D")
			(pintype "passive")
		)
	)
	(footprint "antmicro-footprints:R_0402_1005Metric"
		(layer "F.Cu")
		(at 116.477962 138.2665 90)
		(descr "Resistor SMD 0402")
		(tags "resistor SMD 0402")
		(property "Reference" "R326"
			(at -3.72 0.37 90)
			(layer "F.SilkS")
			(effects
				(font
					(size 0.7 0.7)
					(thickness 0.15)
				)
				(justify left bottom)
			)
		)
		(property "Value" "R_470R_0402"
			(at -1.011843 1.772047 90)
			(layer "F.Fab")
			(effects
				(font
					(size 0.7 0.7)
					(thickness 0.15)
				)
				(justify left bottom)
			)
		)
		(property "Datasheet" "https://www.bourns.com/docs/product-datasheets/cr.pdf"
			(at 0 0 90)
			(layer "F.Fab")
			(hide yes)
			(effects
				(font
					(size 1.27 1.27)
					(thickness 0.15)
				)
			)
		)
		(property "Manufacturer" "Bourns"
			(at 0 0 90)
			(unlocked yes)
			(layer "F.Fab")
			(hide yes)
			(effects
				(font
					(size 1 1)
					(thickness 0.15)
				)
			)
		)
		(property "MPN" "CR0402-FX-4700GLF"
			(at 0 0 90)
			(unlocked yes)
			(layer "F.Fab")
			(hide yes)
			(effects
				(font
					(size 1 1)
					(thickness 0.15)
				)
			)
		)
		(property "Val" "470R"
			(at 0 0 90)
			(unlocked yes)
			(layer "F.Fab")
			(hide yes)
			(effects
				(font
					(size 1 1)
					(thickness 0.15)
				)
			)
		)
		(property "License" "Apache-2.0"
			(at 0 0 90)
			(unlocked yes)
			(layer "F.Fab")
			(hide yes)
			(effects
				(font
					(size 1 1)
					(thickness 0.15)
				)
			)
		)
		(property "Author" "Antmicro"
			(at 0 0 90)
			(unlocked yes)
			(layer "F.Fab")
			(hide yes)
			(effects
				(font
					(size 1 1)
					(thickness 0.15)
				)
			)
		)
		(property "Tolerance" "1%"
			(at 0 0 90)
			(unlocked yes)
			(layer "F.Fab")
			(hide yes)
			(effects
				(font
					(size 1 1)
					(thickness 0.15)
				)
			)
		)
		(sheetname "/Supply/")
		(sheetfile "supply.kicad_sch")
		(attr smd)
		(fp_rect
			(start -0.925 -0.47)
			(end 0.925 0.47)
			(stroke
				(width 0.05)
				(type default)
			)
			(fill no)
			(layer "F.CrtYd")
		)
		(fp_rect
			(start -0.5 -0.25)
			(end 0.5 0.25)
			(stroke
				(width 0.15)
				(type solid)
			)
			(fill no)
			(layer "F.Fab")
		)
		(fp_text user "License: Apache-2.0"
			(at -0.95 5.169 90)
			(layer "F.Fab")
			(effects
				(font
					(size 0.7 0.7)
					(thickness 0.15)
				)
				(justify left bottom)
			)
		)
		(fp_text user "Author: Antmicro"
			(at -0.95 4.169 90)
			(layer "F.Fab")
			(effects
				(font
					(size 0.7 0.7)
					(thickness 0.15)
				)
				(justify left bottom)
			)
		)
		(fp_text user "${REFERENCE}"
			(at -0.95 3.168 90)
			(layer "F.Fab")
			(effects
				(font
					(size 0.7 0.7)
					(thickness 0.15)
				)
				(justify left bottom)
			)
		)
		(pad "1" smd roundrect
			(at -0.48 0 90)
			(size 0.59 0.64)
			(layers "F.Cu" "F.Mask" "F.Paste")
			(roundrect_rratio 0.25)
			(net 475 "Net-(D305-A)")
			(pintype "passive")
		)
		(pad "2" smd roundrect
			(at 0.48 0 90)
			(size 0.59 0.64)
			(layers "F.Cu" "F.Mask" "F.Paste")
			(roundrect_rratio 0.25)
			(net 65 "3V3_SSD")
			(pintype "passive")
		)
	)
	(footprint "antmicro-footprints:C_0402_1005Metric"
		(layer "F.Cu")
		(at 95.592962 138.782236)
		(descr "Capacitor SMD 0402")
		(tags "capacitor SMD 0402")
		(property "Reference" "C916"
			(at 1.235 0.394264 180)
			(layer "F.SilkS")
			(effects
				(font
					(size 0.7 0.7)
					(thickness 0.15)
				)
				(justify left bottom)
			)
		)
		(property "Value" "C_100n_0402"
			(at -1.022927 2.155213 0)
			(layer "F.Fab")
			(effects
				(font
					(size 0.7 0.7)
					(thickness 0.15)
				)
				(justify left bottom)
			)
		)
		(property "Datasheet" "https://www.murata.com/products/productdetail?partno=GRM155R61H104KE14%23"
			(at 0 0 0)
			(layer "F.Fab")
			(hide yes)
			(effects
				(font
					(size 1.27 1.27)
					(thickness 0.15)
				)
			)
		)
		(property "Manufacturer" "Murata"
			(at 0 0 0)
			(unlocked yes)
			(layer "F.Fab")
			(hide yes)
			(effects
				(font
					(size 1 1)
					(thickness 0.15)
				)
			)
		)
		(property "MPN" "GRM155R61H104KE14D"
			(at 0 0 0)
			(unlocked yes)
			(layer "F.Fab")
			(hide yes)
			(effects
				(font
					(size 1 1)
					(thickness 0.15)
				)
			)
		)
		(property "Val" "100n"
			(at 0 0 0)
			(unlocked yes)
			(layer "F.Fab")
			(hide yes)
			(effects
				(font
					(size 1 1)
					(thickness 0.15)
				)
			)
		)
		(property "License" "Apache-2.0"
			(at 0 0 0)
			(unlocked yes)
			(layer "F.Fab")
			(hide yes)
			(effects
				(font
					(size 1 1)
					(thickness 0.15)
				)
			)
		)
		(property "Author" "Antmicro"
			(at 0 0 0)
			(unlocked yes)
			(layer "F.Fab")
			(hide yes)
			(effects
				(font
					(size 1 1)
					(thickness 0.15)
				)
			)
		)
		(property "Voltage" "50V"
			(at 0 0 0)
			(unlocked yes)
			(layer "F.Fab")
			(hide yes)
			(effects
				(font
					(size 1 1)
					(thickness 0.15)
				)
			)
		)
		(property "Dielectric" "X5R"
			(at 0 0 0)
			(unlocked yes)
			(layer "F.Fab")
			(hide yes)
			(effects
				(font
					(size 1 1)
					(thickness 0.15)
				)
			)
		)
		(sheetname "/USB/")
		(sheetfile "usb.kicad_sch")
		(attr smd)
		(fp_rect
			(start -0.925 -0.47)
			(end 0.925 0.47)
			(stroke
				(width 0.05)
				(type default)
			)
			(fill no)
			(layer "F.CrtYd")
		)
		(fp_line
			(start -0.494 -0.25)
			(end 0.504 -0.25)
			(stroke
				(width 0.15)
				(type solid)
			)
			(layer "F.Fab")
		)
		(fp_line
			(start -0.494 0.248)
			(end -0.494 -0.25)
			(stroke
				(width 0.15)
				(type solid)
			)
			(layer "F.Fab")
		)
		(fp_line
			(start 0.504 -0.25)
			(end 0.504 0.248)
			(stroke
				(width 0.15)
				(type solid)
			)
			(layer "F.Fab")
		)
		(fp_line
			(start 0.504 0.248)
			(end -0.494 0.248)
			(stroke
				(width 0.15)
				(type solid)
			)
			(layer "F.Fab")
		)
		(fp_text user "License: Apache-2.0"
			(at -0.939 5.799 0)
			(layer "F.Fab")
			(effects
				(font
					(size 0.7 0.7)
					(thickness 0.15)
				)
				(justify left bottom)
			)
		)
		(fp_text user "Author: Antmicro"
			(at -0.939 3.399 0)
			(layer "F.Fab")
			(effects
				(font
					(size 0.7 0.7)
					(thickness 0.15)
				)
				(justify left bottom)
			)
		)
		(fp_text user "${REFERENCE}"
			(at -0.939 4.599 0)
			(layer "F.Fab")
			(effects
				(font
					(size 0.7 0.7)
					(thickness 0.15)
				)
				(justify left bottom)
			)
		)
		(pad "1" smd roundrect
			(at -0.48 0)
			(size 0.59 0.64)
			(layers "F.Cu" "F.Mask" "F.Paste")
			(roundrect_rratio 0.25)
			(net 30 "/USB/USB_1V2")
			(pintype "passive")
		)
		(pad "2" smd roundrect
			(at 0.48 0)
			(size 0.59 0.64)
			(layers "F.Cu" "F.Mask" "F.Paste")
			(roundrect_rratio 0.25)
			(net 3 "GND")
			(pintype "passive")
		)
	)
)
